(kicad_pcb
	(version 20240108)
	(generator "pcbnew")
	(generator_version "8.0")
	(general
		(thickness 1.62)
		(legacy_teardrops no)
	)
	(paper "A4")
	(title_block
		(title "Jetson Orin Baseboard")
		(date "2025-03-12")
		(rev "1.3.4")
		(company "Antmicro Ltd")
		(comment 1 "www.antmicro.com")
		(comment 9 "footprints 23-26 of 677")
	)
	(layers
		(0 "F.Cu" signal)
		(1 "In1.Cu" signal)
		(2 "In2.Cu" signal)
		(3 "In3.Cu" signal)
		(4 "In4.Cu" jumper)
		(5 "In5.Cu" signal)
		(6 "In6.Cu" signal)
		(31 "B.Cu" signal)
		(32 "B.Adhes" user "B.Adhesive")
		(33 "F.Adhes" user "F.Adhesive")
		(34 "B.Paste" user)
		(35 "F.Paste" user)
		(36 "B.SilkS" user "B.Silkscreen")
		(37 "F.SilkS" user "F.Silkscreen")
		(38 "B.Mask" user)
		(39 "F.Mask" user)
		(40 "Dwgs.User" user "User.Drawings")
		(41 "Cmts.User" user "User.Comments")
		(42 "Eco1.User" user "User.Eco1")
		(43 "Eco2.User" user "User.Eco2")
		(44 "Edge.Cuts" user)
		(45 "Margin" user)
		(46 "B.CrtYd" user "B.Courtyard")
		(47 "F.CrtYd" user "F.Courtyard")
		(48 "B.Fab" user)
		(49 "F.Fab" user)
	)
	(footprint "antmicro-footprints:SOT-523"
		(layer "F.Cu")
		(at 42.109 105.185 90)
		(property "Reference" "Q17"
			(at -1.415 1.141 180)
			(layer "F.SilkS")
			(effects
				(font
					(size 0.7 0.7)
					(thickness 0.15)
				)
				(justify left bottom)
			)
		)
		(property "Value" "PJE138K"
			(at 0.1 1.824 90)
			(layer "F.Fab")
			(effects
				(font
					(size 0.7 0.7)
					(thickness 0.15)
				)
				(justify left bottom)
			)
		)
		(property "Footprint" "antmicro-footprints:SOT-523"
			(at 0 0 90)
			(layer "F.Fab")
			(hide yes)
			(effects
				(font
					(size 1.27 1.27)
					(thickness 0.15)
				)
			)
		)
		(property "Datasheet" "https://www.mouser.com/datasheet/2/1057/PJE138K-1876698.pdf"
			(at 0 0 90)
			(layer "F.Fab")
			(hide yes)
			(effects
				(font
					(size 1.27 1.27)
					(thickness 0.15)
				)
			)
		)
		(property "Author" "Antmicro"
			(at 147.294 63.076 0)
			(layer "F.Fab")
			(hide yes)
			(effects
				(font
					(size 1 1)
					(thickness 0.15)
				)
			)
		)
		(property "License" "Apache-2.0"
			(at 147.294 63.076 0)
			(layer "F.Fab")
			(hide yes)
			(effects
				(font
					(size 1 1)
					(thickness 0.15)
				)
			)
		)
		(property "MPN" "PJE138K_R1_00001"
			(at 147.294 63.076 0)
			(layer "F.Fab")
			(hide yes)
			(effects
				(font
					(size 1 1)
					(thickness 0.15)
				)
			)
		)
		(property "Manufacturer" "PANJIT"
			(at 147.294 63.076 0)
			(layer "F.Fab")
			(hide yes)
			(effects
				(font
					(size 1 1)
					(thickness 0.15)
				)
			)
		)
		(sheetname "Ethernet")
		(sheetfile "ethernet.kicad_sch")
		(attr smd)
		(fp_line
			(start -0.277 -0.551)
			(end -0.277 -0.75)
			(stroke
				(width 0.15)
				(type solid)
			)
			(layer "F.SilkS")
		)
		(fp_line
			(start -0.725 -0.551)
			(end -0.277 -0.551)
			(stroke
				(width 0.15)
				(type solid)
			)
			(layer "F.SilkS")
		)
		(fp_line
			(start -0.927 -0.351)
			(end -0.725 -0.551)
			(stroke
				(width 0.15)
				(type solid)
			)
			(layer "F.SilkS")
		)
		(fp_line
			(start -0.927 -0.051)
			(end -0.927 -0.351)
			(stroke
				(width 0.15)
				(type solid)
			)
			(layer "F.SilkS")
		)
		(fp_circle
			(center -0.9652 0.9652)
			(end -0.9152 0.9652)
			(stroke
				(width 0.15)
				(type solid)
			)
			(fill solid)
			(layer "F.SilkS")
		)
		(fp_line
			(start 1.1 -1.16)
			(end 1.1 1.15)
			(stroke
				(width 0.05)
				(type solid)
			)
			(layer "F.CrtYd")
		)
		(fp_line
			(start -1.12 -1.16)
			(end 1.1 -1.16)
			(stroke
				(width 0.05)
				(type solid)
			)
			(layer "F.CrtYd")
		)
		(fp_line
			(start -1.12 -1.16)
			(end -1.12 1.15)
			(stroke
				(width 0.05)
				(type solid)
			)
			(layer "F.CrtYd")
		)
		(fp_line
			(start -1.12 1.15)
			(end 1.1 1.15)
			(stroke
				(width 0.05)
				(type solid)
			)
			(layer "F.CrtYd")
		)
		(fp_line
			(start 0.8 -0.425)
			(end -0.652 -0.425)
			(stroke
				(width 0.15)
				(type solid)
			)
			(layer "F.Fab")
		)
		(fp_line
			(start 0.8 -0.425)
			(end 0.8 0.424)
			(stroke
				(width 0.15)
				(type solid)
			)
			(layer "F.Fab")
		)
		(fp_line
			(start -0.652 -0.425)
			(end -0.802 -0.276)
			(stroke
				(width 0.15)
				(type solid)
			)
			(layer "F.Fab")
		)
		(fp_line
			(start -0.802 -0.276)
			(end -0.802 0.424)
			(stroke
				(width 0.15)
				(type solid)
			)
			(layer "F.Fab")
		)
		(fp_line
			(start 0.8 0.424)
			(end -0.802 0.424)
			(stroke
				(width 0.15)
				(type solid)
			)
			(layer "F.Fab")
		)
		(fp_circle
			(center -0.9652 0.9652)
			(end -0.9144 0.9652)
			(stroke
				(width 0.15)
				(type solid)
			)
			(fill none)
			(layer "F.Fab")
		)
		(fp_text user "License: Apache-2.0"
			(at -1.12 5.024 90)
			(layer "F.Fab")
			(hide yes)
			(effects
				(font
					(size 0.7 0.7)
					(thickness 0.15)
				)
				(justify left bottom)
			)
		)
		(fp_text user "${REFERENCE}"
			(at -1.12 3.824 90)
			(layer "F.Fab")
			(hide yes)
			(effects
				(font
					(size 0.7 0.7)
					(thickness 0.15)
				)
				(justify left bottom)
			)
		)
		(fp_text user "Author: Antmicro"
			(at -1.12 6.224 90)
			(layer "F.Fab")
			(hide yes)
			(effects
				(font
					(size 0.7 0.7)
					(thickness 0.15)
				)
				(justify left bottom)
			)
		)
		(pad "1" smd rect
			(at -0.5 0.65 90)
			(size 0.4 0.51)
			(layers "F.Cu" "F.Paste" "F.Mask")
			(net 127 "/Ethernet/POE_ACTIVE")
			(pinfunction "G")
			(pintype "passive")
		)
		(pad "2" smd rect
			(at 0.498 0.65 90)
			(size 0.4 0.51)
			(layers "F.Cu" "F.Paste" "F.Mask")
			(net 106 "GNDD")
			(pinfunction "S")
			(pintype "passive")
		)
		(pad "3" smd rect
			(at 0 -0.652 90)
			(size 0.4 0.51)
			(layers "F.Cu" "F.Paste" "F.Mask")
			(net 650 "/Ethernet/ULS-12_CTRL")
			(pinfunction "D")
			(pintype "passive")
		)
	)
	(footprint "antmicro-footprints:R_Array_4x0402"
		(layer "F.Cu")
		(at 137.4 94.71 90)
		(property "Reference" "R26"
			(at -0.99 -0.9 90)
			(layer "F.SilkS")
			(effects
				(font
					(size 0.7 0.7)
					(thickness 0.15)
				)
				(justify left bottom)
			)
		)
		(property "Value" "R_4x330R_0402_array"
			(at -1.5 2 90)
			(layer "F.Fab")
			(effects
				(font
					(size 0.7 0.7)
					(thickness 0.15)
				)
				(justify left bottom)
			)
		)
		(property "Footprint" "antmicro-footprints:R_Array_4x0402"
			(at 0 0 90)
			(layer "F.Fab")
			(hide yes)
			(effects
				(font
					(size 1.27 1.27)
					(thickness 0.15)
				)
			)
		)
		(property "Datasheet" "http://industrial.panasonic.com/cdbs/www-data/pdf/AOC0000/AOC0000C14.pdf"
			(at 0 0 90)
			(layer "F.Fab")
			(hide yes)
			(effects
				(font
					(size 1.27 1.27)
					(thickness 0.15)
				)
			)
		)
		(property "Author" "Antmicro"
			(at 232.11 -42.69 0)
			(layer "F.Fab")
			(hide yes)
			(effects
				(font
					(size 1 1)
					(thickness 0.15)
				)
			)
		)
		(property "License" "Apache-2.0"
			(at 232.11 -42.69 0)
			(layer "F.Fab")
			(hide yes)
			(effects
				(font
					(size 1 1)
					(thickness 0.15)
				)
			)
		)
		(property "MPN" "EXB-28V331JX"
			(at 232.11 -42.69 0)
			(layer "F.Fab")
			(hide yes)
			(effects
				(font
					(size 1 1)
					(thickness 0.15)
				)
			)
		)
		(property "Manufacturer" "Panasonic"
			(at 232.11 -42.69 0)
			(layer "F.Fab")
			(hide yes)
			(effects
				(font
					(size 1 1)
					(thickness 0.15)
				)
			)
		)
		(property "Val" "R_4x330R_0402"
			(at 232.11 -42.69 0)
			(layer "F.Fab")
			(hide yes)
			(effects
				(font
					(size 1 1)
					(thickness 0.15)
				)
			)
		)
		(sheetname "Peripherals")
		(sheetfile "peripherals.kicad_sch")
		(attr smd)
		(fp_line
			(start -1.17 -0.5)
			(end -1.17 0.498)
			(stroke
				(width 0.15)
				(type solid)
			)
			(layer "F.SilkS")
		)
		(fp_line
			(start 1.167 0.498)
			(end 1.167 -0.5)
			(stroke
				(width 0.15)
				(type solid)
			)
			(layer "F.SilkS")
		)
		(fp_rect
			(start -1.2 -0.9)
			(end 1.2 0.9)
			(stroke
				(width 0.05)
				(type solid)
			)
			(fill none)
			(layer "F.CrtYd")
		)
		(fp_line
			(start 0.998 -0.5)
			(end 0.998 0.498)
			(stroke
				(width 0.15)
				(type solid)
			)
			(layer "F.Fab")
		)
		(fp_line
			(start -1 -0.5)
			(end 0.998 -0.5)
			(stroke
				(width 0.15)
				(type solid)
			)
			(layer "F.Fab")
		)
		(fp_line
			(start 0.998 0.498)
			(end -1 0.498)
			(stroke
				(width 0.15)
				(type solid)
			)
			(layer "F.Fab")
		)
		(fp_line
			(start -1 0.498)
			(end -1 -0.5)
			(stroke
				(width 0.15)
				(type solid)
			)
			(layer "F.Fab")
		)
		(fp_text user "License: Apache-2.0"
			(at -1.5 5.75 90)
			(layer "F.Fab")
			(hide yes)
			(effects
				(font
					(size 0.7 0.7)
					(thickness 0.15)
				)
				(justify left bottom)
			)
		)
		(fp_text user "Author: Antmicro"
			(at -1.5 4.5 90)
			(layer "F.Fab")
			(hide yes)
			(effects
				(font
					(size 0.7 0.7)
					(thickness 0.15)
				)
				(justify left bottom)
			)
		)
		(fp_text user "${REFERENCE}"
			(at -1.5 3.25 90)
			(layer "F.Fab")
			(hide yes)
			(effects
				(font
					(size 0.7 0.7)
					(thickness 0.15)
				)
				(justify left bottom)
			)
		)
		(pad "1" smd roundrect
			(at -0.802 0.45 90)
			(size 0.4 0.5)
			(layers "F.Cu" "F.Paste" "F.Mask")
			(roundrect_rratio 0.25)
			(net 515 "/Peripherals/GPIO07_CONN")
			(pinfunction "R1.1")
			(pintype "passive")
		)
		(pad "2" smd roundrect
			(at -0.272 0.45 90)
			(size 0.4 0.5)
			(layers "F.Cu" "F.Paste" "F.Mask")
			(roundrect_rratio 0.25)
			(net 348 "/Peripherals/GPIO01_CONN")
			(pinfunction "R2.1")
			(pintype "passive")
		)
		(pad "3" smd roundrect
			(at 0.27 0.45 90)
			(size 0.4 0.5)
			(layers "F.Cu" "F.Paste" "F.Mask")
			(roundrect_rratio 0.25)
			(net 346 "/Peripherals/PCIE2_CLKREQ_CONN*")
			(pinfunction "R3.1")
			(pintype "passive")
		)
		(pad "4" smd roundrect
			(at 0.8 0.45 90)
			(size 0.4 0.5)
			(layers "F.Cu" "F.Paste" "F.Mask")
			(roundrect_rratio 0.25)
			(net 345 "/Peripherals/PCIE2_RST_CONN*")
			(pinfunction "R4.1")
			(pintype "passive")
		)
		(pad "5" smd roundrect
			(at 0.8 -0.452 90)
			(size 0.4 0.5)
			(layers "F.Cu" "F.Paste" "F.Mask")
			(roundrect_rratio 0.25)
			(net 103 "PCIE2_RST*")
			(pinfunction "R4.2")
			(pintype "passive")
		)
		(pad "6" smd roundrect
			(at 0.27 -0.452 90)
			(size 0.4 0.5)
			(layers "F.Cu" "F.Paste" "F.Mask")
			(roundrect_rratio 0.25)
			(net 104 "PCIE2_CLKREQ*")
			(pinfunction "R3.2")
			(pintype "passive")
		)
		(pad "7" smd roundrect
			(at -0.272 -0.452 90)
			(size 0.4 0.5)
			(layers "F.Cu" "F.Paste" "F.Mask")
			(roundrect_rratio 0.25)
			(net 43 "GPIO01")
			(pinfunction "R2.2")
			(pintype "passive")
		)
		(pad "8" smd roundrect
			(at -0.802 -0.452 90)
			(size 0.4 0.5)
			(layers "F.Cu" "F.Paste" "F.Mask")
			(roundrect_rratio 0.25)
			(net 102 "GPIO07")
			(pinfunction "R1.2")
			(pintype "passive")
		)
	)
	(footprint "antmicro-footprints:SOT-523"
		(layer "F.Cu")
		(at 87.5 100.2 -90)
		(property "Reference" "Q2"
			(at -1.23 0.72 0)
			(layer "F.SilkS")
			(effects
				(font
					(size 0.7 0.7)
					(thickness 0.15)
				)
				(justify left bottom)
			)
		)
		(property "Value" "PJE138K"
			(at 0.1 1.824 -90)
			(layer "F.Fab")
			(effects
				(font
					(size 0.7 0.7)
					(thickness 0.15)
				)
				(justify left bottom)
			)
		)
		(property "Footprint" "antmicro-footprints:SOT-523"
			(at 0 0 -90)
			(layer "F.Fab")
			(hide yes)
			(effects
				(font
					(size 1.27 1.27)
					(thickness 0.15)
				)
			)
		)
		(property "Datasheet" "https://www.mouser.com/datasheet/2/1057/PJE138K-1876698.pdf"
			(at 0 0 -90)
			(layer "F.Fab")
			(hide yes)
			(effects
				(font
					(size 1.27 1.27)
					(thickness 0.15)
				)
			)
		)
		(property "Author" "Antmicro"
			(at -12.7 187.7 0)
			(layer "F.Fab")
			(hide yes)
			(effects
				(font
					(size 1 1)
					(thickness 0.15)
				)
			)
		)
		(property "License" "Apache-2.0"
			(at -12.7 187.7 0)
			(layer "F.Fab")
			(hide yes)
			(effects
				(font
					(size 1 1)
					(thickness 0.15)
				)
			)
		)
		(property "MPN" "PJE138K_R1_00001"
			(at -12.7 187.7 0)
			(layer "F.Fab")
			(hide yes)
			(effects
				(font
					(size 1 1)
					(thickness 0.15)
				)
			)
		)
		(property "Manufacturer" "PANJIT"
			(at -12.7 187.7 0)
			(layer "F.Fab")
			(hide yes)
			(effects
				(font
					(size 1 1)
					(thickness 0.15)
				)
			)
		)
		(sheetname "HDMI")
		(sheetfile "hdmi.kicad_sch")
		(attr smd)
		(fp_line
			(start -0.927 -0.051)
			(end -0.927 -0.351)
			(stroke
				(width 0.15)
				(type solid)
			)
			(layer "F.SilkS")
		)
		(fp_line
			(start -0.927 -0.351)
			(end -0.725 -0.551)
			(stroke
				(width 0.15)
				(type solid)
			)
			(layer "F.SilkS")
		)
		(fp_line
			(start -0.725 -0.551)
			(end -0.277 -0.551)
			(stroke
				(width 0.15)
				(type solid)
			)
			(layer "F.SilkS")
		)
		(fp_line
			(start -0.277 -0.551)
			(end -0.277 -0.75)
			(stroke
				(width 0.15)
				(type solid)
			)
			(layer "F.SilkS")
		)
		(fp_circle
			(center -0.9652 0.9652)
			(end -0.9152 0.9652)
			(stroke
				(width 0.15)
				(type solid)
			)
			(fill solid)
			(layer "F.SilkS")
		)
		(fp_line
			(start -1.12 1.15)
			(end 1.1 1.15)
			(stroke
				(width 0.05)
				(type solid)
			)
			(layer "F.CrtYd")
		)
		(fp_line
			(start -1.12 -1.16)
			(end -1.12 1.15)
			(stroke
				(width 0.05)
				(type solid)
			)
			(layer "F.CrtYd")
		)
		(fp_line
			(start -1.12 -1.16)
			(end 1.1 -1.16)
			(stroke
				(width 0.05)
				(type solid)
			)
			(layer "F.CrtYd")
		)
		(fp_line
			(start 1.1 -1.16)
			(end 1.1 1.15)
			(stroke
				(width 0.05)
				(type solid)
			)
			(layer "F.CrtYd")
		)
		(fp_line
			(start 0.8 0.424)
			(end -0.802 0.424)
			(stroke
				(width 0.15)
				(type solid)
			)
			(layer "F.Fab")
		)
		(fp_line
			(start -0.802 -0.276)
			(end -0.802 0.424)
			(stroke
				(width 0.15)
				(type solid)
			)
			(layer "F.Fab")
		)
		(fp_line
			(start -0.652 -0.425)
			(end -0.802 -0.276)
			(stroke
				(width 0.15)
				(type solid)
			)
			(layer "F.Fab")
		)
		(fp_line
			(start 0.8 -0.425)
			(end 0.8 0.424)
			(stroke
				(width 0.15)
				(type solid)
			)
			(layer "F.Fab")
		)
		(fp_line
			(start 0.8 -0.425)
			(end -0.652 -0.425)
			(stroke
				(width 0.15)
				(type solid)
			)
			(layer "F.Fab")
		)
		(fp_circle
			(center -0.9652 0.9652)
			(end -0.9144 0.9652)
			(stroke
				(width 0.15)
				(type solid)
			)
			(fill none)
			(layer "F.Fab")
		)
		(fp_text user "Author: Antmicro"
			(at -1.12 6.224 -90)
			(layer "F.Fab")
			(hide yes)
			(effects
				(font
					(size 0.7 0.7)
					(thickness 0.15)
				)
				(justify left bottom)
			)
		)
		(fp_text user "${REFERENCE}"
			(at -1.12 3.824 -90)
			(layer "F.Fab")
			(hide yes)
			(effects
				(font
					(size 0.7 0.7)
					(thickness 0.15)
				)
				(justify left bottom)
			)
		)
		(fp_text user "License: Apache-2.0"
			(at -1.12 5.024 -90)
			(layer "F.Fab")
			(hide yes)
			(effects
				(font
					(size 0.7 0.7)
					(thickness 0.15)
				)
				(justify left bottom)
			)
		)
		(pad "1" smd rect
			(at -0.5 0.65 270)
			(size 0.4 0.51)
			(layers "F.Cu" "F.Paste" "F.Mask")
			(net 87 "+3V3")
			(pinfunction "G")
			(pintype "passive")
		)
		(pad "2" smd rect
			(at 0.498 0.65 270)
			(size 0.4 0.51)
			(layers "F.Cu" "F.Paste" "F.Mask")
			(net 1 "GND")
			(pinfunction "S")
			(pintype "passive")
		)
		(pad "3" smd rect
			(at 0 -0.652 270)
			(size 0.4 0.51)
			(layers "F.Cu" "F.Paste" "F.Mask")
			(net 623 "Net-(Q2-D)")
			(pinfunction "D")
			(pintype "passive")
		)
	)
	(footprint "antmicro-footprints:R_0402_1005Metric"
		(layer "F.Cu")
		(at 109.8 102.65 -90)
		(descr "Resistor SMD 0402")
		(tags "resistor SMD 0402")
		(property "Reference" "R125"
			(at -0.82 -0.07 -90)
			(layer "F.SilkS")
			(effects
				(font
					(size 0.7 0.7)
					(thickness 0.15)
				)
				(justify left bottom)
			)
		)
		(property "Value" "R_0R_0402"
			(at 0 1.4 -90)
			(layer "F.Fab")
			(effects
				(font
					(size 0.7 0.7)
					(thickness 0.15)
				)
				(justify left bottom)
			)
		)
		(property "Footprint" "antmicro-footprints:R_0402_1005Metric"
			(at 0 0 -90)
			(layer "F.Fab")
			(hide yes)
			(effects
				(font
					(size 1.27 1.27)
					(thickness 0.15)
				)
			)
		)
		(property "Datasheet" "https://industrial.panasonic.com/cdbs/www-data/pdf/RDA0000/AOA0000C301.pdf"
			(at 0 0 -90)
			(layer "F.Fab")
			(hide yes)
			(effects
				(font
					(size 1.27 1.27)
					(thickness 0.15)
				)
			)
		)
		(property "Author" "Antmicro"
			(at 7.15 212.45 0)
			(layer "F.Fab")
			(hide yes)
			(effects
				(font
					(size 1 1)
					(thickness 0.15)
				)
			)
		)
		(property "Current" "1A"
			(at 7.15 212.45 0)
			(layer "F.Fab")
			(hide yes)
			(effects
				(font
					(size 1 1)
					(thickness 0.15)
				)
			)
		)
		(property "License" "Apache-2.0"
			(at 7.15 212.45 0)
			(layer "F.Fab")
			(hide yes)
			(effects
				(font
					(size 1 1)
					(thickness 0.15)
				)
			)
		)
		(property "MPN" "ERJ2GE0R00X"
			(at 7.15 212.45 0)
			(layer "F.Fab")
			(hide yes)
			(effects
				(font
					(size 1 1)
					(thickness 0.15)
				)
			)
		)
		(property "Manufacturer" "Panasonic"
			(at 7.15 212.45 0)
			(layer "F.Fab")
			(hide yes)
			(effects
				(font
					(size 1 1)
					(thickness 0.15)
				)
			)
		)
		(property "Tolerance" ""
			(at 7.15 212.45 0)
			(layer "F.Fab")
			(hide yes)
			(effects
				(font
					(size 1 1)
					(thickness 0.15)
				)
			)
		)
		(property "Val" "0R"
			(at 7.15 212.45 0)
			(layer "F.Fab")
			(hide yes)
			(effects
				(font
					(size 1 1)
					(thickness 0.15)
				)
			)
		)
		(sheetname "USB3")
		(sheetfile "usb3.kicad_sch")
		(attr smd exclude_from_pos_files exclude_from_bom dnp)
		(fp_rect
			(start -0.925 -0.47)
			(end 0.925 0.47)
			(stroke
				(width 0.05)
				(type default)
			)
			(fill none)
			(layer "F.CrtYd")
		)
		(fp_rect
			(start -0.5 -0.25)
			(end 0.5 0.25)
			(stroke
				(width 0.15)
				(type solid)
			)
			(fill none)
			(layer "F.Fab")
		)
		(fp_text user "${REFERENCE}"
			(at -0.95 3.168 -90)
			(layer "F.Fab")
			(hide yes)
			(effects
				(font
					(size 0.7 0.7)
					(thickness 0.15)
				)
				(justify left bottom)
			)
		)
		(fp_text user "License: Apache-2.0"
			(at -0.95 5.169 -90)
			(layer "F.Fab")
			(hide yes)
			(effects
				(font
					(size 0.7 0.7)
					(thickness 0.15)
				)
				(justify left bottom)
			)
		)
		(fp_text user "Author: Antmicro"
			(at -0.95 4.169 -90)
			(layer "F.Fab")
			(hide yes)
			(effects
				(font
					(size 0.7 0.7)
					(thickness 0.15)
				)
				(justify left bottom)
			)
		)
		(pad "1" smd roundrect
			(at -0.48 0 270)
			(size 0.59 0.64)
			(layers "F.Cu" "F.Paste" "F.Mask")
			(roundrect_rratio 0.25)
			(net 252 "SYS_SCL")
			(pintype "passive")
		)
		(pad "2" smd roundrect
			(at 0.48 0 270)
			(size 0.59 0.64)
			(layers "F.Cu" "F.Paste" "F.Mask")
			(roundrect_rratio 0.25)
			(net 363 "/USB3/USBC1_ISC_SCL")
			(pintype "passive")
		)
	)
)
